# T6G (Grand Teton) — schematic netlist excerpt (pin names and nets, part order shuffled) for the footprints in the layout excerpt that follows; sources: Cadence DE-HDL packaged netlist, KiCad conversion of 04192023_DAF0TMB3IC0_F0TG_MB_C_brd_V02_OCP.brd

C2508  Q_CAP  22UF 4V 20% X6S  pkg C0402  page 74 : A = PVDD11_S3_P1 ; B = GND
R3683  Q_RES  0 5% EMPTY  pkg 0402LF  page 257 : A = P3V3_ADC ; B = P3V3_ADC_MAM

(kicad_pcb
	(version 20260206)
	(generator "pcbnew")
	(generator_version "10.0")
	(general
		(thickness 1.6)
		(legacy_teardrops no)
	)
	(paper "A4")
	(title_block
		(title "04192023_DAF0TMB3IC0_F0TG_MB_C_brd_V02_OCP.brd")
		(comment 1 "Grand Teton / footprints 4806-4807 of 8354")
	)
	(layers
		(0 "F.Cu" signal "TOP")
		(4 "In1.Cu" signal "GND")
		(6 "In2.Cu" signal "IN1")
		(8 "In3.Cu" signal "GND1")
		(10 "In4.Cu" signal "IN2")
		(12 "In5.Cu" signal "GND2")
		(14 "In6.Cu" signal "IN3")
		(16 "In7.Cu" signal "GND3")
		(18 "In8.Cu" signal "VCC")
		(20 "In9.Cu" signal "VCC1")
		(22 "In10.Cu" signal "GND4")
		(24 "In11.Cu" signal "IN4")
		(26 "In12.Cu" signal "GND5")
		(28 "In13.Cu" signal "IN5")
		(30 "In14.Cu" signal "GND6")
		(32 "In15.Cu" signal "IN6")
		(34 "In16.Cu" signal "GND7")
		(2 "B.Cu" signal "BOTTOM")
		(9 "F.Adhes" user "F.Adhesive")
		(11 "B.Adhes" user "B.Adhesive")
		(13 "F.Paste" user "Package Geometry/Pastemask Top")
		(15 "B.Paste" user "Package Geometry/Pastemask Bottom")
		(5 "F.SilkS" user "Ref Des/Silkscreen Top")
		(7 "B.SilkS" user "Ref Des/Silkscreen Bottom")
		(1 "F.Mask" user "Board Geometry/Soldermask Top")
		(3 "B.Mask" user "Board Geometry/Soldermask Bottom")
		(17 "Dwgs.User" user "User.Drawings")
		(19 "Cmts.User" user "User.Comments")
		(21 "Eco1.User" user "User.Eco1")
		(23 "Eco2.User" user "User.Eco2")
		(25 "Edge.Cuts" user "Board Geometry/Outline")
		(27 "Margin" user)
		(31 "F.CrtYd" user "Package Geometry/Place Bound Top")
		(29 "B.CrtYd" user "Package Geometry/Place Bound Bottom")
		(35 "F.Fab" user "Ref Des/Assembly Top")
		(33 "B.Fab" user "Ref Des/Assembly Bottom")
	)
	(footprint ""
		(layer "F.Cu")
		(at 323.637148 -42.176954)
		(property "Reference" "R3683"
			(at 0 0 0)
			(layer "F.SilkS")
			(hide yes)
			(effects
				(font
					(size 1.27 1.27)
				)
			)
		)
		(property "Value" ""
			(at 0 0 0)
			(layer "F.Fab")
			(effects
				(font
					(size 1.27 1.27)
				)
			)
		)
		(duplicate_pad_numbers_are_jumpers no)
		(fp_line
			(start -0.7874 -0.4064)
			(end 0.7874 -0.4064)
			(stroke
				(width 0.1524)
				(type default)
			)
			(layer "F.SilkS")
		)
		(fp_line
			(start -0.7874 0.4064)
			(end -0.7874 -0.4064)
			(stroke
				(width 0.1524)
				(type default)
			)
			(layer "F.SilkS")
		)
		(fp_line
			(start 0.7874 -0.4064)
			(end 0.7874 0.4064)
			(stroke
				(width 0.1524)
				(type default)
			)
			(layer "F.SilkS")
		)
		(fp_line
			(start 0.7874 0.4064)
			(end -0.7874 0.4064)
			(stroke
				(width 0.1524)
				(type default)
			)
			(layer "F.SilkS")
		)
		(fp_line
			(start -0.67945 -0.305054)
			(end -0.12065 -0.305054)
			(stroke
				(width 0.1)
				(type default)
			)
			(layer "F.Fab")
		)
		(fp_line
			(start -0.67945 0.3048)
			(end -0.67945 -0.305054)
			(stroke
				(width 0.1)
				(type default)
			)
			(layer "F.Fab")
		)
		(fp_line
			(start -0.12065 -0.305054)
			(end -0.12065 -0.2794)
			(stroke
				(width 0.1)
				(type default)
			)
			(layer "F.Fab")
		)
		(fp_line
			(start -0.12065 -0.2794)
			(end 0.12065 -0.2794)
			(stroke
				(width 0.1)
				(type default)
			)
			(layer "F.Fab")
		)
		(fp_line
			(start -0.12065 0.2794)
			(end -0.12065 0.3048)
			(stroke
				(width 0.1)
				(type default)
			)
			(layer "F.Fab")
		)
		(fp_line
			(start -0.12065 0.3048)
			(end -0.67945 0.3048)
			(stroke
				(width 0.1)
				(type default)
			)
			(layer "F.Fab")
		)
		(fp_line
			(start 0.120396 0.2794)
			(end -0.12065 0.2794)
			(stroke
				(width 0.1)
				(type default)
			)
			(layer "F.Fab")
		)
		(fp_line
			(start 0.120396 0.3048)
			(end 0.120396 0.2794)
			(stroke
				(width 0.1)
				(type default)
			)
			(layer "F.Fab")
		)
		(fp_line
			(start 0.12065 -0.3048)
			(end 0.67945 -0.3048)
			(stroke
				(width 0.1)
				(type default)
			)
			(layer "F.Fab")
		)
		(fp_line
			(start 0.12065 -0.2794)
			(end 0.12065 -0.3048)
			(stroke
				(width 0.1)
				(type default)
			)
			(layer "F.Fab")
		)
		(fp_line
			(start 0.67945 -0.3048)
			(end 0.67945 0.3048)
			(stroke
				(width 0.1)
				(type default)
			)
			(layer "F.Fab")
		)
		(fp_line
			(start 0.67945 0.3048)
			(end 0.120396 0.3048)
			(stroke
				(width 0.1)
				(type default)
			)
			(layer "F.Fab")
		)
		(pad "1" smd rect
			(at -0.40005 0 180)
			(size 0.4572 0.508)
			(layers "F.Cu" "F.Mask" "F.Paste")
			(net "P3V3_ADC")
		)
		(pad "2" smd rect
			(at 0.40005 0 180)
			(size 0.4572 0.508)
			(layers "F.Cu" "F.Mask" "F.Paste")
			(net "P3V3_ADC_MAM")
		)
	)
	(footprint ""
		(layer "F.Cu")
		(at 116.227098 -261.748016 -90)
		(property "Reference" "C2508"
			(at 0 0 270)
			(layer "F.SilkS")
			(hide yes)
			(effects
				(font
					(size 1.27 1.27)
				)
			)
		)
		(property "Value" ""
			(at 0 0 270)
			(layer "F.Fab")
			(effects
				(font
					(size 1.27 1.27)
				)
			)
		)
		(duplicate_pad_numbers_are_jumpers no)
		(fp_line
			(start -0.7874 0.4064)
			(end -0.7874 -0.4064)
			(stroke
				(width 0.1524)
				(type default)
			)
			(layer "F.SilkS")
		)
		(fp_line
			(start 0.7874 0.4064)
			(end -0.7874 0.4064)
			(stroke
				(width 0.1524)
				(type default)
			)
			(layer "F.SilkS")
		)
		(fp_line
			(start -0.7874 -0.4064)
			(end 0.7874 -0.4064)
			(stroke
				(width 0.1524)
				(type default)
			)
			(layer "F.SilkS")
		)
		(fp_line
			(start 0.7874 -0.4064)
			(end 0.7874 0.4064)
			(stroke
				(width 0.1524)
				(type default)
			)
			(layer "F.SilkS")
		)
		(fp_line
			(start -0.67945 0.3048)
			(end -0.67945 -0.305054)
			(stroke
				(width 0.1)
				(type default)
			)
			(layer "F.Fab")
		)
		(fp_line
			(start -0.12065 0.3048)
			(end -0.67945 0.3048)
			(stroke
				(width 0.1)
				(type default)
			)
			(layer "F.Fab")
		)
		(fp_line
			(start 0.120396 0.3048)
			(end 0.120396 0.2794)
			(stroke
				(width 0.1)
				(type default)
			)
			(layer "F.Fab")
		)
		(fp_line
			(start 0.67945 0.3048)
			(end 0.120396 0.3048)
			(stroke
				(width 0.1)
				(type default)
			)
			(layer "F.Fab")
		)
		(fp_line
			(start -0.12065 0.2794)
			(end -0.12065 0.3048)
			(stroke
				(width 0.1)
				(type default)
			)
			(layer "F.Fab")
		)
		(fp_line
			(start 0.120396 0.2794)
			(end -0.12065 0.2794)
			(stroke
				(width 0.1)
				(type default)
			)
			(layer "F.Fab")
		)
		(fp_line
			(start -0.12065 -0.2794)
			(end 0.12065 -0.2794)
			(stroke
				(width 0.1)
				(type default)
			)
			(layer "F.Fab")
		)
		(fp_line
			(start 0.12065 -0.2794)
			(end 0.12065 -0.3048)
			(stroke
				(width 0.1)
				(type default)
			)
			(layer "F.Fab")
		)
		(fp_line
			(start 0.12065 -0.3048)
			(end 0.67945 -0.3048)
			(stroke
				(width 0.1)
				(type default)
			)
			(layer "F.Fab")
		)
		(fp_line
			(start 0.67945 -0.3048)
			(end 0.67945 0.3048)
			(stroke
				(width 0.1)
				(type default)
			)
			(layer "F.Fab")
		)
		(fp_line
			(start -0.67945 -0.305054)
			(end -0.12065 -0.305054)
			(stroke
				(width 0.1)
				(type default)
			)
			(layer "F.Fab")
		)
		(fp_line
			(start -0.12065 -0.305054)
			(end -0.12065 -0.2794)
			(stroke
				(width 0.1)
				(type default)
			)
			(layer "F.Fab")
		)
		(pad "1" smd circle
			(at -0.40005 0 270)
			(size 0 0)
			(layers "F.Cu" "F.Mask" "F.Paste")
			(net "PVDD11_S3_P1")
		)
		(pad "2" smd circle
			(at 0.40005 0 270)
			(size 0 0)
			(layers "F.Cu" "F.Mask" "F.Paste")
			(net "GND")
		)
	)
)
